(kicad_pcb
	(version 20260206)
	(generator "pcbnew")
	(generator_version "10.0")
	(general
		(thickness 1.6)
		(legacy_teardrops no)
	)
	(paper "A4")
	(title_block
		(title "Bryce Canyon_F.DPB_16315-1-OCP.brd")
		(comment 1 "Bryce Canyon / footprints 615-621 of 2223")
	)
	(layers
		(0 "F.Cu" signal "TOP")
		(4 "In1.Cu" signal "L2GND")
		(6 "In2.Cu" signal "L3")
		(8 "In3.Cu" signal "L4GND")
		(10 "In4.Cu" signal "L5")
		(12 "In5.Cu" signal "L6VCC")
		(14 "In6.Cu" signal "L7VCC")
		(16 "In7.Cu" signal "L8")
		(18 "In8.Cu" signal "L9GND")
		(20 "In9.Cu" signal "L10")
		(22 "In10.Cu" signal "L11GND")
		(2 "B.Cu" signal "BOTTOM")
		(9 "F.Adhes" user "F.Adhesive")
		(11 "B.Adhes" user "B.Adhesive")
		(13 "F.Paste" user "Package Geometry/Pastemask Top")
		(15 "B.Paste" user "Package Geometry/Pastemask Bottom")
		(5 "F.SilkS" user "Ref Des/Silkscreen Top")
		(7 "B.SilkS" user "Ref Des/Silkscreen Bottom")
		(1 "F.Mask" user "Board Geometry/Soldermask Top")
		(3 "B.Mask" user "Board Geometry/Soldermask Bottom")
		(17 "Dwgs.User" user "User.Drawings")
		(19 "Cmts.User" user "User.Comments")
		(21 "Eco1.User" user "User.Eco1")
		(23 "Eco2.User" user "User.Eco2")
		(25 "Edge.Cuts" user "Board Geometry/Outline")
		(27 "Margin" user)
		(31 "F.CrtYd" user "Package Geometry/Place Bound Top")
		(29 "B.CrtYd" user "Package Geometry/Place Bound Bottom")
		(35 "F.Fab" user "Ref Des/Assembly Top")
		(33 "B.Fab" user "Ref Des/Assembly Bottom")
	)
	(footprint ""
		(layer "F.Cu")
		(at 368.354102 -292.016942)
		(property "Reference" "Q44"
			(at 0 0 0)
			(layer "F.SilkS")
			(hide yes)
			(effects
				(font
					(size 1.27 1.27)
				)
			)
		)
		(property "Value" "AO4407AL-GP"
			(at -3.707384 -1.5367 0)
			(unlocked yes)
			(layer "F.Fab")
			(hide yes)
			(effects
				(font
					(size 1.016 1.016)
					(thickness 0.1524)
				)
			)
		)
		(property "Device Type" "SOIC8H69"
			(at -3.707384 -3.0607 0)
			(unlocked yes)
			(layer "F.Fab")
			(hide yes)
			(effects
				(font
					(size 1.016 1.016)
					(thickness 0.1524)
				)
			)
		)
		(duplicate_pad_numbers_are_jumpers no)
		(fp_line
			(start -2.7432 -1.4224)
			(end -2.7432 1.4224)
			(stroke
				(width 0.1524)
				(type default)
			)
			(layer "F.SilkS")
		)
		(fp_line
			(start -2.7432 1.4224)
			(end -2.6416 1.4224)
			(stroke
				(width 0.1524)
				(type default)
			)
			(layer "F.SilkS")
		)
		(fp_line
			(start -2.7432 1.4224)
			(end 2.1336 1.4224)
			(stroke
				(width 0.1524)
				(type default)
			)
			(layer "F.SilkS")
		)
		(fp_line
			(start -2.7178 -0.508)
			(end -2.1844 -0.0508)
			(stroke
				(width 0.1524)
				(type default)
			)
			(layer "F.SilkS")
		)
		(fp_line
			(start -2.6289 3.4417)
			(end -2.6289 1.4732)
			(stroke
				(width 0.381)
				(type default)
			)
			(layer "F.SilkS")
		)
		(fp_line
			(start -2.1844 -0.0508)
			(end -2.7178 0.508)
			(stroke
				(width 0.1524)
				(type default)
			)
			(layer "F.SilkS")
		)
		(fp_line
			(start 2.1336 -1.4224)
			(end -2.7432 -1.4224)
			(stroke
				(width 0.1524)
				(type default)
			)
			(layer "F.SilkS")
		)
		(fp_line
			(start 2.1336 1.4224)
			(end 2.1336 -1.4224)
			(stroke
				(width 0.1524)
				(type default)
			)
			(layer "F.SilkS")
		)
		(fp_poly
			(pts
				(xy -2.2098 -1.4224) (xy -2.2098 1.4224) (xy 2.2098 1.4224) (xy 2.2098 -1.4224)
			)
			(stroke
				(width 0)
				(type default)
			)
			(fill yes)
			(layer "F.SilkS")
		)
		(fp_rect
			(start -2.450084 2.999994)
			(end 2.450084 -2.999994)
			(stroke
				(width 0)
				(type default)
			)
			(fill no)
			(layer "F.CrtYd")
		)
		(fp_poly
			(pts
				(xy -2.8194 3.6322) (xy -2.8194 -3.6322) (xy 2.8194 -3.6322) (xy 2.8194 1.18364) (xy 2.450084 1.18364)
				(xy 2.450084 -2.999994) (xy -2.450084 -2.999994) (xy -2.450084 2.999994) (xy 2.450084 2.999994)
				(xy 2.450084 1.18618) (xy 2.8194 1.18618) (xy 2.8194 3.6322)
			)
			(stroke
				(width 0)
				(type default)
			)
			(fill no)
			(layer "F.CrtYd")
		)
		(fp_rect
			(start -2.8194 3.6322)
			(end 2.8194 -3.6322)
			(stroke
				(width 0)
				(type default)
			)
			(fill no)
			(layer "F.Fab")
		)
		(pad "1" smd rect
			(at -1.905 2.54)
			(size 0.635 1.651)
			(layers "F.Cu" "F.Mask" "F.Paste")
			(net "P12V_A")
		)
		(pad "2" smd rect
			(at -0.635 2.54)
			(size 0.635 1.651)
			(layers "F.Cu" "F.Mask" "F.Paste")
			(net "P12V_A")
		)
		(pad "3" smd rect
			(at 0.635 2.54)
			(size 0.635 1.651)
			(layers "F.Cu" "F.Mask" "F.Paste")
			(net "P12V_A")
		)
		(pad "4" smd rect
			(at 1.905 2.54)
			(size 0.635 1.651)
			(layers "F.Cu" "F.Mask" "F.Paste")
			(net "SW_HDD_N7")
		)
		(pad "5" smd rect
			(at 1.905 -2.54)
			(size 0.635 1.651)
			(layers "F.Cu" "F.Mask" "F.Paste")
			(net "P12V_HDD7")
		)
		(pad "6" smd rect
			(at 0.635 -2.54)
			(size 0.635 1.651)
			(layers "F.Cu" "F.Mask" "F.Paste")
			(net "P12V_HDD7")
		)
		(pad "7" smd rect
			(at -0.635 -2.54)
			(size 0.635 1.651)
			(layers "F.Cu" "F.Mask" "F.Paste")
			(net "P12V_HDD7")
		)
		(pad "8" smd rect
			(at -1.905 -2.54)
			(size 0.635 1.651)
			(layers "F.Cu" "F.Mask" "F.Paste")
			(net "P12V_HDD7")
		)
	)
	(footprint ""
		(layer "F.Cu")
		(at 162.118802 -127.703072 180)
		(property "Reference" "Q244"
			(at 0 0 180)
			(layer "F.SilkS")
			(hide yes)
			(effects
				(font
					(size 1.27 1.27)
				)
			)
		)
		(property "Value" "2N7002K-2-GP"
			(at 0.127 -8.9662 180)
			(unlocked yes)
			(layer "F.Fab")
			(hide yes)
			(effects
				(font
					(size 1.016 1.016)
					(thickness 0.1524)
				)
			)
		)
		(property "Device Type" "SOT23DGS2D4H44"
			(at 0.127 -10.4902 180)
			(unlocked yes)
			(layer "F.Fab")
			(hide yes)
			(effects
				(font
					(size 1.016 1.016)
					(thickness 0.1524)
				)
			)
		)
		(duplicate_pad_numbers_are_jumpers no)
		(fp_line
			(start 1.651 1.778)
			(end 1.651 -1.778)
			(stroke
				(width 0.1524)
				(type default)
			)
			(layer "F.SilkS")
		)
		(fp_line
			(start 1.651 -1.778)
			(end -1.651 -1.778)
			(stroke
				(width 0.1524)
				(type default)
			)
			(layer "F.SilkS")
		)
		(fp_line
			(start -1.651 1.778)
			(end 1.651 1.778)
			(stroke
				(width 0.1524)
				(type default)
			)
			(layer "F.SilkS")
		)
		(fp_line
			(start -1.651 -1.778)
			(end -1.651 1.778)
			(stroke
				(width 0.1524)
				(type default)
			)
			(layer "F.SilkS")
		)
		(fp_poly
			(pts
				(xy -1.778 1.8796) (xy -1.778 -1.8796) (xy 1.778 -1.8796) (xy 1.778 1.8796)
			)
			(stroke
				(width 0)
				(type default)
			)
			(fill no)
			(layer "F.CrtYd")
		)
		(fp_poly
			(pts
				(xy -1.778 1.8796) (xy -1.778 -1.8796) (xy 1.778 -1.8796) (xy 1.778 1.8796)
			)
			(stroke
				(width 0)
				(type default)
			)
			(fill no)
			(layer "F.Fab")
		)
		(pad "D" smd custom
			(at 0 -0.9525 180)
			(size 0.1905 0.1905)
			(layers "F.Cu" "F.Mask" "F.Paste")
			(net "FLT_HDD17_N")
			(options
				(clearance outline)
				(anchor circle)
			)
			(primitives
				(gr_poly
					(pts
						(arc
							(start -0.1778 0.5715)
							(mid -0.321484 0.511984)
							(end -0.381 0.3683)
						)
						(arc
							(start -0.381 -0.3683)
							(mid -0.321484 -0.511984)
							(end -0.1778 -0.5715)
						)
						(arc
							(start 0.1778 -0.5715)
							(mid 0.321484 -0.511984)
							(end 0.381 -0.3683)
						)
						(arc
							(start 0.381 0.3683)
							(mid 0.321484 0.511984)
							(end 0.1778 0.5715)
						)
					)
					(width 0)
					(fill yes)
				)
			)
		)
		(pad "G" smd custom
			(at -0.98425 0.9525 180)
			(size 0.1905 0.1905)
			(layers "F.Cu" "F.Mask" "F.Paste")
			(net "DRIVE_A_17_FLT_LED")
			(options
				(clearance outline)
				(anchor circle)
			)
			(primitives
				(gr_poly
					(pts
						(arc
							(start -0.1778 0.5715)
							(mid -0.321484 0.511984)
							(end -0.381 0.3683)
						)
						(arc
							(start -0.381 -0.3683)
							(mid -0.321484 -0.511984)
							(end -0.1778 -0.5715)
						)
						(arc
							(start 0.1778 -0.5715)
							(mid 0.321484 -0.511984)
							(end 0.381 -0.3683)
						)
						(arc
							(start 0.381 0.3683)
							(mid 0.321484 0.511984)
							(end 0.1778 0.5715)
						)
					)
					(width 0)
					(fill yes)
				)
			)
		)
		(pad "S" smd custom
			(at 0.98425 0.9525 180)
			(size 0.1905 0.1905)
			(layers "F.Cu" "F.Mask" "F.Paste")
			(net "GND")
			(options
				(clearance outline)
				(anchor circle)
			)
			(primitives
				(gr_poly
					(pts
						(arc
							(start -0.1778 0.5715)
							(mid -0.321484 0.511984)
							(end -0.381 0.3683)
						)
						(arc
							(start -0.381 -0.3683)
							(mid -0.321484 -0.511984)
							(end -0.1778 -0.5715)
						)
						(arc
							(start 0.1778 -0.5715)
							(mid 0.321484 -0.511984)
							(end 0.381 -0.3683)
						)
						(arc
							(start 0.381 0.3683)
							(mid 0.321484 0.511984)
							(end 0.1778 0.5715)
						)
					)
					(width 0)
					(fill yes)
				)
			)
		)
	)
	(footprint ""
		(layer "F.Cu")
		(at 477.739202 -273.940016 90)
		(property "Reference" "VIA6"
			(at 0 0 90)
			(layer "F.SilkS")
			(hide yes)
			(effects
				(font
					(size 1.27 1.27)
				)
			)
		)
		(property "Value" "100OHM-8L-1D6MM-L18L16-GP"
			(at -3.7211 -4.5085 90)
			(unlocked yes)
			(layer "F.Fab")
			(hide yes)
			(effects
				(font
					(size 1.016 1.016)
					(thickness 0.1524)
				)
			)
		)
		(property "Device Type" "VIA-PCIE-4P-394076"
			(at -3.7211 -6.0325 90)
			(unlocked yes)
			(layer "F.Fab")
			(hide yes)
			(effects
				(font
					(size 1.016 1.016)
					(thickness 0.1524)
				)
			)
		)
		(duplicate_pad_numbers_are_jumpers no)
		(fp_rect
			(start -1.9685 0.381)
			(end 1.9685 -0.381)
			(stroke
				(width 0)
				(type default)
			)
			(fill no)
			(layer "F.CrtYd")
		)
		(fp_rect
			(start -1.9685 0.381)
			(end 1.9685 -0.381)
			(stroke
				(width 0)
				(type default)
			)
			(fill no)
			(layer "F.Fab")
		)
		(pad "1" thru_hole circle
			(at -1.5875 0 90)
			(size 0.508 0.508)
			(drill 0.254)
			(layers "*.Cu" "*.Mask")
			(remove_unused_layers no)
			(net "GND")
			(clearance 0.127)
			(thermal_gap 0.127)
		)
		(pad "2" thru_hole circle
			(at -0.5715 0 90)
			(size 0.508 0.508)
			(drill 0.254)
			(layers "*.Cu" "*.Mask")
			(remove_unused_layers no)
			(net "PHY_SCC_A_TO_DRV_A_11_DP")
			(clearance 0.127)
			(thermal_gap 0.127)
		)
		(pad "3" thru_hole circle
			(at 0.5715 0 90)
			(size 0.508 0.508)
			(drill 0.254)
			(layers "*.Cu" "*.Mask")
			(remove_unused_layers no)
			(net "PHY_SCC_A_TO_DRV_A_11_DN")
			(clearance 0.127)
			(thermal_gap 0.127)
		)
		(pad "4" thru_hole circle
			(at 1.5875 0 90)
			(size 0.508 0.508)
			(drill 0.254)
			(layers "*.Cu" "*.Mask")
			(remove_unused_layers no)
			(net "GND")
			(clearance 0.127)
			(thermal_gap 0.127)
		)
	)
	(footprint ""
		(layer "F.Cu")
		(at 22.996398 -274.871942 -90)
		(property "Reference" "R968"
			(at 0 0 270)
			(layer "F.SilkS")
			(hide yes)
			(effects
				(font
					(size 1.27 1.27)
				)
			)
		)
		(property "Value" "0R2J-2-GP"
			(at 0.064008 -3.993896 270)
			(unlocked yes)
			(layer "F.Fab")
			(hide yes)
			(effects
				(font
					(size 1.016 1.016)
					(thickness 0.1524)
				)
			)
		)
		(property "Device Type" "R402H16"
			(at 0.064008 -5.517896 270)
			(unlocked yes)
			(layer "F.Fab")
			(hide yes)
			(effects
				(font
					(size 1.016 1.016)
					(thickness 0.1524)
				)
			)
		)
		(duplicate_pad_numbers_are_jumpers no)
		(fp_line
			(start -0.508 -0.9398)
			(end -0.508 0.9398)
			(stroke
				(width 0.1524)
				(type default)
			)
			(layer "F.SilkS")
		)
		(fp_line
			(start 0.508 -0.9398)
			(end -0.508 -0.9398)
			(stroke
				(width 0.1524)
				(type default)
			)
			(layer "F.SilkS")
		)
		(fp_rect
			(start -0.508 0.9398)
			(end 0.508 -0.9398)
			(stroke
				(width 0)
				(type default)
			)
			(fill no)
			(layer "F.CrtYd")
		)
		(fp_rect
			(start -0.508 0.9398)
			(end 0.508 -0.9398)
			(stroke
				(width 0)
				(type default)
			)
			(fill no)
			(layer "F.Fab")
		)
		(pad "1" smd custom
			(at 0 -0.4445 270)
			(size 0.1397 0.1397)
			(layers "F.Cu" "F.Mask" "F.Paste")
			(net "DRIVE_A_0_PWR")
			(options
				(clearance outline)
				(anchor circle)
			)
			(primitives
				(gr_poly
					(pts
						(arc
							(start -0.1778 -0.2794)
							(mid -0.249642 -0.249642)
							(end -0.2794 -0.1778)
						)
						(arc
							(start -0.2794 0.1778)
							(mid -0.249642 0.249642)
							(end -0.1778 0.2794)
						)
						(arc
							(start 0.1778 0.2794)
							(mid 0.249642 0.249642)
							(end 0.2794 0.1778)
						)
						(arc
							(start 0.2794 -0.1778)
							(mid 0.249642 -0.249642)
							(end 0.1778 -0.2794)
						)
					)
					(width 0)
					(fill yes)
				)
			)
		)
		(pad "2" smd custom
			(at 0 0.4445 270)
			(size 0.1397 0.1397)
			(layers "F.Cu" "F.Mask" "F.Paste")
			(net "SW_PWR_R_HDD0")
			(options
				(clearance outline)
				(anchor circle)
			)
			(primitives
				(gr_poly
					(pts
						(arc
							(start -0.1778 -0.2794)
							(mid -0.249642 -0.249642)
							(end -0.2794 -0.1778)
						)
						(arc
							(start -0.2794 0.1778)
							(mid -0.249642 0.249642)
							(end -0.1778 0.2794)
						)
						(arc
							(start 0.1778 0.2794)
							(mid 0.249642 0.249642)
							(end 0.2794 0.1778)
						)
						(arc
							(start 0.2794 -0.1778)
							(mid 0.249642 -0.249642)
							(end 0.1778 -0.2794)
						)
					)
					(width 0)
					(fill yes)
				)
			)
		)
	)
	(footprint ""
		(layer "F.Cu")
		(at 109.365796 -179.683918 -90)
		(property "Reference" "C240"
			(at 0 0 270)
			(layer "F.SilkS")
			(hide yes)
			(effects
				(font
					(size 1.27 1.27)
				)
			)
		)
		(property "Value" "SC4D7U25V5KX-1-GP"
			(at -0.0762 -6.1214 270)
			(unlocked yes)
			(layer "F.Fab")
			(hide yes)
			(effects
				(font
					(size 1.016 1.016)
					(thickness 0.1524)
				)
			)
		)
		(property "Device Type" "C805H58"
			(at -0.0762 -8.1534 270)
			(unlocked yes)
			(layer "F.Fab")
			(hide yes)
			(effects
				(font
					(size 1.016 1.016)
					(thickness 0.1524)
				)
			)
		)
		(duplicate_pad_numbers_are_jumpers no)
		(fp_line
			(start 0.635 0)
			(end -0.635 0)
			(stroke
				(width 0.508)
				(type default)
			)
			(layer "F.SilkS")
		)
		(fp_rect
			(start -0.9652 1.778)
			(end 0.9652 -1.778)
			(stroke
				(width 0)
				(type default)
			)
			(fill no)
			(layer "F.CrtYd")
		)
		(fp_poly
			(pts
				(xy -0.9652 -1.778) (xy 0.9652 -1.778) (xy 0.9652 1.778) (xy -0.9652 1.778)
			)
			(stroke
				(width 0)
				(type default)
			)
			(fill no)
			(layer "F.Fab")
		)
		(pad "1" smd rect
			(at 0 -0.9652 270)
			(size 1.397 1.143)
			(layers "F.Cu" "F.Mask" "F.Paste")
			(net "P12V_HDD15")
		)
		(pad "2" smd rect
			(at 0 0.9652 270)
			(size 1.397 1.143)
			(layers "F.Cu" "F.Mask" "F.Paste")
			(net "GND")
		)
	)
	(footprint ""
		(layer "F.Cu")
		(at 86.832948 -62.270894)
		(property "Reference" "R727"
			(at 0 0 0)
			(layer "F.SilkS")
			(hide yes)
			(effects
				(font
					(size 1.27 1.27)
				)
			)
		)
		(property "Value" "2R6F-GP"
			(at -0.0508 -4.8514 0)
			(unlocked yes)
			(layer "F.Fab")
			(hide yes)
			(effects
				(font
					(size 1.016 1.016)
					(thickness 0.1524)
				)
			)
		)
		(property "Device Type" "R1206H26"
			(at 0 -6.3754 0)
			(unlocked yes)
			(layer "F.Fab")
			(hide yes)
			(effects
				(font
					(size 1.016 1.016)
					(thickness 0.1524)
				)
			)
		)
		(duplicate_pad_numbers_are_jumpers no)
		(fp_line
			(start -1.016 -2.2352)
			(end 1.016 -2.2352)
			(stroke
				(width 0.1524)
				(type default)
			)
			(layer "F.SilkS")
		)
		(fp_line
			(start -1.016 2.2352)
			(end -1.016 -2.2352)
			(stroke
				(width 0.1524)
				(type default)
			)
			(layer "F.SilkS")
		)
		(fp_line
			(start 1.016 -2.2352)
			(end 1.016 2.2352)
			(stroke
				(width 0.1524)
				(type default)
			)
			(layer "F.SilkS")
		)
		(fp_line
			(start 1.016 2.2352)
			(end -1.016 2.2352)
			(stroke
				(width 0.1524)
				(type default)
			)
			(layer "F.SilkS")
		)
		(fp_rect
			(start -1.0922 2.3114)
			(end 1.0922 -2.3114)
			(stroke
				(width 0)
				(type default)
			)
			(fill no)
			(layer "F.CrtYd")
		)
		(fp_poly
			(pts
				(xy -1.0922 -2.3114) (xy 1.0922 -2.3114) (xy 1.0922 2.3114) (xy -1.0922 2.3114)
			)
			(stroke
				(width 0)
				(type default)
			)
			(fill no)
			(layer "F.Fab")
		)
		(pad "1" smd rect
			(at 0 -1.397)
			(size 1.651 1.27)
			(layers "F.Cu" "F.Mask" "F.Paste")
			(net "P5V_HDD26")
		)
		(pad "2" smd rect
			(at 0 1.397)
			(size 1.651 1.27)
			(layers "F.Cu" "F.Mask" "F.Paste")
			(net "5V_PRE_26")
		)
	)
	(footprint ""
		(layer "F.Cu")
		(at 256.921 -236.347 -90)
		(property "Reference" "R129"
			(at 0 0 270)
			(layer "F.SilkS")
			(hide yes)
			(effects
				(font
					(size 1.27 1.27)
				)
			)
		)
		(property "Value" "100KR2F-L1-GP"
			(at 0.064008 -3.993896 270)
			(unlocked yes)
			(layer "F.Fab")
			(hide yes)
			(effects
				(font
					(size 1.016 1.016)
					(thickness 0.1524)
				)
			)
		)
		(property "Device Type" "R402H16"
			(at 0.064008 -5.517896 270)
			(unlocked yes)
			(layer "F.Fab")
			(hide yes)
			(effects
				(font
					(size 1.016 1.016)
					(thickness 0.1524)
				)
			)
		)
		(duplicate_pad_numbers_are_jumpers no)
		(fp_line
			(start -0.508 -0.9398)
			(end -0.508 0.9398)
			(stroke
				(width 0.1524)
				(type default)
			)
			(layer "F.SilkS")
		)
		(fp_line
			(start 0.508 -0.9398)
			(end -0.508 -0.9398)
			(stroke
				(width 0.1524)
				(type default)
			)
			(layer "F.SilkS")
		)
		(fp_rect
			(start -0.508 0.9398)
			(end 0.508 -0.9398)
			(stroke
				(width 0)
				(type default)
			)
			(fill no)
			(layer "F.CrtYd")
		)
		(fp_rect
			(start -0.508 0.9398)
			(end 0.508 -0.9398)
			(stroke
				(width 0)
				(type default)
			)
			(fill no)
			(layer "F.Fab")
		)
		(pad "1" smd custom
			(at 0 -0.4445 270)
			(size 0.1397 0.1397)
			(layers "F.Cu" "F.Mask" "F.Paste")
			(net "GPIO_VCC_U9")
			(options
				(clearance outline)
				(anchor circle)
			)
			(primitives
				(gr_poly
					(pts
						(arc
							(start -0.1778 -0.2794)
							(mid -0.249642 -0.249642)
							(end -0.2794 -0.1778)
						)
						(arc
							(start -0.2794 0.1778)
							(mid -0.249642 0.249642)
							(end -0.1778 0.2794)
						)
						(arc
							(start 0.1778 0.2794)
							(mid 0.249642 0.249642)
							(end 0.2794 0.1778)
						)
						(arc
							(start 0.2794 -0.1778)
							(mid 0.249642 -0.249642)
							(end 0.1778 -0.2794)
						)
					)
					(width 0)
					(fill yes)
				)
			)
		)
		(pad "2" smd custom
			(at 0 0.4445 270)
			(size 0.1397 0.1397)
			(layers "F.Cu" "F.Mask" "F.Paste")
			(net "GND")
			(options
				(clearance outline)
				(anchor circle)
			)
			(primitives
				(gr_poly
					(pts
						(arc
							(start -0.1778 -0.2794)
							(mid -0.249642 -0.249642)
							(end -0.2794 -0.1778)
						)
						(arc
							(start -0.2794 0.1778)
							(mid -0.249642 0.249642)
							(end -0.1778 0.2794)
						)
						(arc
							(start 0.1778 0.2794)
							(mid 0.249642 0.249642)
							(end 0.2794 0.1778)
						)
						(arc
							(start 0.2794 -0.1778)
							(mid 0.249642 -0.249642)
							(end 0.1778 -0.2794)
						)
					)
					(width 0)
					(fill yes)
				)
			)
		)
	)
)
